# T6G (Grand Teton) — schematic netlist excerpt (pin names and nets, part order shuffled) for the footprints in the layout excerpt that follows; sources: Cadence DE-HDL packaged netlist, KiCad conversion of 04192023_DAF0TMB3IC0_F0TG_MB_C_brd_V02_OCP.brd

C6617  Q_CAP_DIFFBUS  DIFF BUS_0.22UF 6.3V 20% X6S  pkg C0201  page 308 : \1\ = P5E_CPU0_P3_TX_BUF_C_DP<10> ; \2\ = P5E_CPU0_P3_TX_BUF_DP<10>
R8070  Q_RES  1K 1% CHIP  pkg 0402LF  page 200 : A = PVDD18_S5_P0 ; B = PVDDCR_CPU1_P0_RESET_N_R

(kicad_pcb
	(version 20260206)
	(generator "pcbnew")
	(generator_version "10.0")
	(general
		(thickness 1.6)
		(legacy_teardrops no)
	)
	(paper "A4")
	(title_block
		(title "04192023_DAF0TMB3IC0_F0TG_MB_C_brd_V02_OCP.brd")
		(comment 1 "Grand Teton / footprints 5566-5567 of 8354")
	)
	(layers
		(0 "F.Cu" signal "TOP")
		(4 "In1.Cu" signal "GND")
		(6 "In2.Cu" signal "IN1")
		(8 "In3.Cu" signal "GND1")
		(10 "In4.Cu" signal "IN2")
		(12 "In5.Cu" signal "GND2")
		(14 "In6.Cu" signal "IN3")
		(16 "In7.Cu" signal "GND3")
		(18 "In8.Cu" signal "VCC")
		(20 "In9.Cu" signal "VCC1")
		(22 "In10.Cu" signal "GND4")
		(24 "In11.Cu" signal "IN4")
		(26 "In12.Cu" signal "GND5")
		(28 "In13.Cu" signal "IN5")
		(30 "In14.Cu" signal "GND6")
		(32 "In15.Cu" signal "IN6")
		(34 "In16.Cu" signal "GND7")
		(2 "B.Cu" signal "BOTTOM")
		(9 "F.Adhes" user "F.Adhesive")
		(11 "B.Adhes" user "B.Adhesive")
		(13 "F.Paste" user "Package Geometry/Pastemask Top")
		(15 "B.Paste" user "Package Geometry/Pastemask Bottom")
		(5 "F.SilkS" user "Ref Des/Silkscreen Top")
		(7 "B.SilkS" user "Ref Des/Silkscreen Bottom")
		(1 "F.Mask" user "Board Geometry/Soldermask Top")
		(3 "B.Mask" user "Board Geometry/Soldermask Bottom")
		(17 "Dwgs.User" user "User.Drawings")
		(19 "Cmts.User" user "User.Comments")
		(21 "Eco1.User" user "User.Eco1")
		(23 "Eco2.User" user "User.Eco2")
		(25 "Edge.Cuts" user "Board Geometry/Outline")
		(27 "Margin" user)
		(31 "F.CrtYd" user "Package Geometry/Place Bound Top")
		(29 "B.CrtYd" user "Package Geometry/Place Bound Bottom")
		(35 "F.Fab" user "Ref Des/Assembly Top")
		(33 "B.Fab" user "Ref Des/Assembly Bottom")
	)
	(footprint ""
		(layer "B.Cu")
		(at 304.419 -360.426 180)
		(property "Reference" "R8070"
			(at 0 0 0)
			(layer "B.SilkS")
			(hide yes)
			(effects
				(font
					(size 1.27 1.27)
				)
				(justify mirror)
			)
		)
		(property "Value" ""
			(at 0 0 0)
			(layer "B.Fab")
			(effects
				(font
					(size 1.27 1.27)
				)
				(justify mirror)
			)
		)
		(duplicate_pad_numbers_are_jumpers no)
		(fp_line
			(start 0.7874 0.4064)
			(end 0.7874 -0.4064)
			(stroke
				(width 0.1524)
				(type default)
			)
			(layer "B.SilkS")
		)
		(fp_line
			(start 0.7874 -0.4064)
			(end -0.7874 -0.4064)
			(stroke
				(width 0.1524)
				(type default)
			)
			(layer "B.SilkS")
		)
		(fp_line
			(start -0.7874 0.4064)
			(end 0.7874 0.4064)
			(stroke
				(width 0.1524)
				(type default)
			)
			(layer "B.SilkS")
		)
		(fp_line
			(start -0.7874 -0.4064)
			(end -0.7874 0.4064)
			(stroke
				(width 0.1524)
				(type default)
			)
			(layer "B.SilkS")
		)
		(fp_line
			(start 0.67945 0.3048)
			(end 0.67945 -0.305054)
			(stroke
				(width 0.1)
				(type default)
			)
			(layer "B.Fab")
		)
		(fp_line
			(start 0.67945 -0.305054)
			(end 0.12065 -0.305054)
			(stroke
				(width 0.1)
				(type default)
			)
			(layer "B.Fab")
		)
		(fp_line
			(start 0.12065 0.3048)
			(end 0.67945 0.3048)
			(stroke
				(width 0.1)
				(type default)
			)
			(layer "B.Fab")
		)
		(fp_line
			(start 0.12065 0.2794)
			(end 0.12065 0.3048)
			(stroke
				(width 0.1)
				(type default)
			)
			(layer "B.Fab")
		)
		(fp_line
			(start 0.12065 -0.2794)
			(end -0.12065 -0.2794)
			(stroke
				(width 0.1)
				(type default)
			)
			(layer "B.Fab")
		)
		(fp_line
			(start 0.12065 -0.305054)
			(end 0.12065 -0.2794)
			(stroke
				(width 0.1)
				(type default)
			)
			(layer "B.Fab")
		)
		(fp_line
			(start -0.120396 0.3048)
			(end -0.120396 0.2794)
			(stroke
				(width 0.1)
				(type default)
			)
			(layer "B.Fab")
		)
		(fp_line
			(start -0.120396 0.2794)
			(end 0.12065 0.2794)
			(stroke
				(width 0.1)
				(type default)
			)
			(layer "B.Fab")
		)
		(fp_line
			(start -0.12065 -0.2794)
			(end -0.12065 -0.3048)
			(stroke
				(width 0.1)
				(type default)
			)
			(layer "B.Fab")
		)
		(fp_line
			(start -0.12065 -0.3048)
			(end -0.67945 -0.3048)
			(stroke
				(width 0.1)
				(type default)
			)
			(layer "B.Fab")
		)
		(fp_line
			(start -0.67945 0.3048)
			(end -0.120396 0.3048)
			(stroke
				(width 0.1)
				(type default)
			)
			(layer "B.Fab")
		)
		(fp_line
			(start -0.67945 -0.3048)
			(end -0.67945 0.3048)
			(stroke
				(width 0.1)
				(type default)
			)
			(layer "B.Fab")
		)
		(pad "1" smd circle
			(at 0.40005 0)
			(size 0 0)
			(layers "B.Cu" "B.Mask" "B.Paste")
			(net "PVDD18_S5_P0")
		)
		(pad "2" smd circle
			(at -0.40005 0)
			(size 0 0)
			(layers "B.Cu" "B.Mask" "B.Paste")
			(net "PVDDCR_CPU1_P0_RESET_N_R")
		)
	)
	(footprint ""
		(layer "B.Cu")
		(at 403.947122 -416.899344 90)
		(property "Reference" "C6617"
			(at 0 0 90)
			(layer "B.SilkS")
			(hide yes)
			(effects
				(font
					(size 1.27 1.27)
				)
				(justify mirror)
			)
		)
		(property "Value" ""
			(at 0 0 90)
			(layer "B.Fab")
			(effects
				(font
					(size 1.27 1.27)
				)
				(justify mirror)
			)
		)
		(duplicate_pad_numbers_are_jumpers no)
		(fp_line
			(start 0.299974 -0.150114)
			(end -0.299974 -0.150114)
			(stroke
				(width 0.1)
				(type default)
			)
			(layer "B.Fab")
		)
		(fp_line
			(start -0.299974 -0.150114)
			(end -0.299974 0.150114)
			(stroke
				(width 0.1)
				(type default)
			)
			(layer "B.Fab")
		)
		(fp_line
			(start 0.299974 0.150114)
			(end 0.299974 -0.150114)
			(stroke
				(width 0.1)
				(type default)
			)
			(layer "B.Fab")
		)
		(fp_line
			(start -0.299974 0.150114)
			(end 0.299974 0.150114)
			(stroke
				(width 0.1)
				(type default)
			)
			(layer "B.Fab")
		)
		(pad "1" smd rect
			(at 0.2667 0 270)
			(size 0.3048 0.381)
			(layers "B.Cu" "B.Mask" "B.Paste")
			(net "P5E_CPU0_P3_TX_BUF_C_DP<10>")
		)
		(pad "2" smd rect
			(at -0.2667 0 270)
			(size 0.3048 0.381)
			(layers "B.Cu" "B.Mask" "B.Paste")
			(net "P5E_CPU0_P3_TX_BUF_DP<10>")
		)
	)
)
